(kicad_pcb
	(version 20241229)
	(generator "pcbnew")
	(generator_version "9.0")
	(general
		(thickness 1.62)
		(legacy_teardrops no)
	)
	(paper "A4")
	(title_block
		(title "OCuLink to 10GbE adapter")
		(date "2026-02-23")
		(rev "1.1.0")
		(company "Antmicro Ltd")
		(comment 1 "www.antmicro.com")
		(comment 9 "footprints 281-285 of 510")
	)
	(layers
		(0 "F.Cu" signal)
		(4 "In1.Cu" signal)
		(6 "In2.Cu" signal)
		(8 "In3.Cu" signal)
		(10 "In4.Cu" signal)
		(12 "In5.Cu" signal)
		(14 "In6.Cu" signal)
		(2 "B.Cu" signal)
		(9 "F.Adhes" user "F.Adhesive")
		(11 "B.Adhes" user "B.Adhesive")
		(13 "F.Paste" user)
		(15 "B.Paste" user)
		(5 "F.SilkS" user "F.Silkscreen")
		(7 "B.SilkS" user "B.Silkscreen")
		(1 "F.Mask" user)
		(3 "B.Mask" user)
		(17 "Dwgs.User" user "User.Drawings")
		(19 "Cmts.User" user "User.Comments")
		(21 "Eco1.User" user "User.Eco1")
		(23 "Eco2.User" user "User.Eco2")
		(25 "Edge.Cuts" user)
		(27 "Margin" user)
		(31 "F.CrtYd" user "F.Courtyard")
		(29 "B.CrtYd" user "B.Courtyard")
		(35 "F.Fab" user)
		(33 "B.Fab" user)
	)
	(footprint "antmicro-footprints:LED_0603_1608Metric_G"
		(layer "F.Cu")
		(at 54.35 122.75 180)
		(descr "LED SMD 0603 Green")
		(tags "LED SMD 0603 Green")
		(property "Reference" "D18"
			(at -1.1 -0.75 0)
			(layer "F.SilkS")
			(effects
				(font
					(size 0.7 0.7)
					(thickness 0.15)
				)
				(justify right top)
			)
		)
		(property "Value" "LED_G_0603_LG_L29K-G2J1-24-Z"
			(at -0.001 1.599 0)
			(layer "F.Fab")
			(hide yes)
			(effects
				(font
					(size 0.7 0.7)
					(thickness 0.15)
				)
				(justify right top)
			)
		)
		(property "Datasheet" "https://look.ams-osram.com/m/19ee86b3ae0ee95b/original/LG-L29K.pdf"
			(at 0 0 0)
			(layer "F.Fab")
			(hide yes)
			(effects
				(font
					(size 1.27 1.27)
					(thickness 0.15)
				)
			)
		)
		(property "Description" "LED, Green, SMD, 0603, 20 mA, 1.7 V, 570 nm"
			(at 0 0 0)
			(layer "F.Fab")
			(hide yes)
			(effects
				(font
					(size 1.27 1.27)
					(thickness 0.15)
				)
			)
		)
		(property "MPN" "LG L29K-G2J1-24-Z"
			(at 0 0 180)
			(unlocked yes)
			(layer "F.Fab")
			(hide yes)
			(effects
				(font
					(size 1 1)
					(thickness 0.15)
				)
			)
		)
		(property "Manufacturer" "OSRAM"
			(at 0 0 180)
			(unlocked yes)
			(layer "F.Fab")
			(hide yes)
			(effects
				(font
					(size 1 1)
					(thickness 0.15)
				)
			)
		)
		(property "Color" "Green"
			(at 0 0 180)
			(unlocked yes)
			(layer "F.Fab")
			(hide yes)
			(effects
				(font
					(size 1 1)
					(thickness 0.15)
				)
			)
		)
		(property "Author" "Antmicro"
			(at 0 0 180)
			(unlocked yes)
			(layer "F.Fab")
			(hide yes)
			(effects
				(font
					(size 1 1)
					(thickness 0.15)
				)
			)
		)
		(property "License" "Apache-2.0"
			(at 0 0 180)
			(unlocked yes)
			(layer "F.Fab")
			(hide yes)
			(effects
				(font
					(size 1 1)
					(thickness 0.15)
				)
			)
		)
		(sheetname "/Power/")
		(sheetfile "power.kicad_sch")
		(attr smd)
		(fp_line
			(start 0.22 0.35)
			(end -0.22 0.35)
			(stroke
				(width 0.15)
				(type solid)
			)
			(layer "F.SilkS")
		)
		(fp_line
			(start 0.22 -0.35)
			(end -0.22 -0.35)
			(stroke
				(width 0.15)
				(type solid)
			)
			(layer "F.SilkS")
		)
		(fp_line
			(start 0.105328 0.201008)
			(end 0.105328 -0.198992)
			(stroke
				(width 0.1)
				(type solid)
			)
			(layer "F.SilkS")
		)
		(fp_line
			(start 0.105328 0.201008)
			(end -0.094672 0.001008)
			(stroke
				(width 0.1)
				(type solid)
			)
			(layer "F.SilkS")
		)
		(fp_line
			(start 0.105328 0.001008)
			(end 0.24 0.001)
			(stroke
				(width 0.1)
				(type solid)
			)
			(layer "F.SilkS")
		)
		(fp_line
			(start -0.094672 0.201008)
			(end -0.094672 -0.198992)
			(stroke
				(width 0.1)
				(type solid)
			)
			(layer "F.SilkS")
		)
		(fp_line
			(start -0.094672 0.001008)
			(end 0.105328 -0.198992)
			(stroke
				(width 0.1)
				(type solid)
			)
			(layer "F.SilkS")
		)
		(fp_line
			(start -0.094672 0.001008)
			(end -0.24 0.001008)
			(stroke
				(width 0.1)
				(type solid)
			)
			(layer "F.SilkS")
		)
		(fp_line
			(start -1.18 -0.319)
			(end -1.18 0.321)
			(stroke
				(width 0.15)
				(type solid)
			)
			(layer "F.SilkS")
		)
		(fp_rect
			(start 1.25 0.65)
			(end -1.25 -0.65)
			(stroke
				(width 0.05)
				(type solid)
			)
			(fill no)
			(layer "F.CrtYd")
		)
		(fp_line
			(start 0.599 0)
			(end 0.201 0)
			(stroke
				(width 0.15)
				(type solid)
			)
			(layer "F.Fab")
		)
		(fp_line
			(start 0.201 0.2)
			(end 0.201 0)
			(stroke
				(width 0.15)
				(type solid)
			)
			(layer "F.Fab")
		)
		(fp_line
			(start 0.201 0)
			(end 0.201 -0.202)
			(stroke
				(width 0.15)
				(type solid)
			)
			(layer "F.Fab")
		)
		(fp_line
			(start 0.201 -0.202)
			(end -0.101 0)
			(stroke
				(width 0.15)
				(type solid)
			)
			(layer "F.Fab")
		)
		(fp_line
			(start -0.101 0)
			(end 0.201 0.2)
			(stroke
				(width 0.15)
				(type solid)
			)
			(layer "F.Fab")
		)
		(fp_line
			(start -0.199 0.2)
			(end -0.199 0.1)
			(stroke
				(width 0.15)
				(type solid)
			)
			(layer "F.Fab")
		)
		(fp_line
			(start -0.199 0)
			(end -0.597 0)
			(stroke
				(width 0.15)
				(type solid)
			)
			(layer "F.Fab")
		)
		(fp_line
			(start -0.199 -0.202)
			(end -0.199 0.1)
			(stroke
				(width 0.15)
				(type solid)
			)
			(layer "F.Fab")
		)
		(fp_rect
			(start 0.848 0.4)
			(end -0.85 -0.402)
			(stroke
				(width 0.15)
				(type solid)
			)
			(fill no)
			(layer "F.Fab")
		)
		(fp_text user "License: Apache-2.0"
			(at -1.4224 3.599 180)
			(layer "F.Fab")
			(effects
				(font
					(size 0.7 0.7)
					(thickness 0.15)
				)
				(justify left bottom)
			)
		)
		(fp_text user "${REFERENCE}"
			(at -1.4224 5.999 180)
			(layer "F.Fab")
			(effects
				(font
					(size 0.7 0.7)
					(thickness 0.15)
				)
				(justify left bottom)
			)
		)
		(fp_text user "Author: Antmicro"
			(at -1.4224 4.799 180)
			(layer "F.Fab")
			(effects
				(font
					(size 0.7 0.7)
					(thickness 0.15)
				)
				(justify left bottom)
			)
		)
		(pad "1" smd roundrect
			(at -0.7 0)
			(size 0.8 1)
			(layers "F.Cu" "F.Mask" "F.Paste")
			(roundrect_rratio 0.2)
			(net 412 "Net-(D18-C)")
			(pinfunction "C")
			(pintype "passive")
		)
		(pad "2" smd roundrect
			(at 0.7 0)
			(size 0.8 1)
			(layers "F.Cu" "F.Mask" "F.Paste")
			(roundrect_rratio 0.2)
			(net 255 "/Power/+3V3_OUT")
			(pinfunction "A")
			(pintype "passive")
		)
	)
	(footprint "antmicro-footprints:R_0402_1005Metric"
		(layer "F.Cu")
		(at 73.85 76.039996 180)
		(descr "Resistor SMD 0402")
		(tags "resistor SMD 0402")
		(property "Reference" "R2"
			(at -1 3.439994 0)
			(layer "F.SilkS")
			(effects
				(font
					(size 0.7 0.7)
					(thickness 0.15)
				)
				(justify right top)
			)
		)
		(property "Value" "R_255k_0402"
			(at -1.011843 1.772046 0)
			(layer "F.Fab")
			(hide yes)
			(effects
				(font
					(size 0.7 0.7)
					(thickness 0.15)
				)
				(justify right top)
			)
		)
		(property "Datasheet" "https://www.bourns.com/docs/product-datasheets/cr.pdf"
			(at 0 0 0)
			(layer "F.Fab")
			(hide yes)
			(effects
				(font
					(size 1.27 1.27)
					(thickness 0.15)
				)
			)
		)
		(property "Description" "SMD Chip Resistor, 255 kohm, ± 1%, 100 mW, 0402 [1005 Metric], Thick Film, Precision"
			(at 0 0 0)
			(layer "F.Fab")
			(hide yes)
			(effects
				(font
					(size 1.27 1.27)
					(thickness 0.15)
				)
			)
		)
		(property "MPN" "CR0402-FX-2553GLF"
			(at 0 0 180)
			(unlocked yes)
			(layer "F.Fab")
			(hide yes)
			(effects
				(font
					(size 1 1)
					(thickness 0.15)
				)
			)
		)
		(property "Manufacturer" "Bourns"
			(at 0 0 180)
			(unlocked yes)
			(layer "F.Fab")
			(hide yes)
			(effects
				(font
					(size 1 1)
					(thickness 0.15)
				)
			)
		)
		(property "License" "Apache-2.0"
			(at 0 0 180)
			(unlocked yes)
			(layer "F.Fab")
			(hide yes)
			(effects
				(font
					(size 1 1)
					(thickness 0.15)
				)
			)
		)
		(property "Author" "Antmicro"
			(at 0 0 180)
			(unlocked yes)
			(layer "F.Fab")
			(hide yes)
			(effects
				(font
					(size 1 1)
					(thickness 0.15)
				)
			)
		)
		(property "Val" "255k"
			(at 0 0 180)
			(unlocked yes)
			(layer "F.Fab")
			(hide yes)
			(effects
				(font
					(size 1 1)
					(thickness 0.15)
				)
			)
		)
		(property "Tolerance" "1%"
			(at 0 0 180)
			(unlocked yes)
			(layer "F.Fab")
			(hide yes)
			(effects
				(font
					(size 1 1)
					(thickness 0.15)
				)
			)
		)
		(sheetname "/Power/")
		(sheetfile "power.kicad_sch")
		(attr smd)
		(fp_rect
			(start -0.925 -0.47)
			(end 0.925 0.47)
			(stroke
				(width 0.05)
				(type default)
			)
			(fill no)
			(layer "F.CrtYd")
		)
		(fp_rect
			(start -0.5 -0.25)
			(end 0.5 0.25)
			(stroke
				(width 0.15)
				(type solid)
			)
			(fill no)
			(layer "F.Fab")
		)
		(pad "1" smd roundrect
			(at -0.48 0 180)
			(size 0.59 0.64)
			(layers "F.Cu" "F.Mask" "F.Paste")
			(roundrect_rratio 0.25)
			(net 379 "/Power/3V3_EN")
			(pintype "passive")
		)
		(pad "2" smd roundrect
			(at 0.48 0 180)
			(size 0.59 0.64)
			(layers "F.Cu" "F.Mask" "F.Paste")
			(roundrect_rratio 0.25)
			(net 314 "VCC")
			(pintype "passive")
		)
	)
	(footprint "antmicro-footprints:R_0402_1005Metric"
		(layer "F.Cu")
		(at 99.35 105.2)
		(descr "Resistor SMD 0402")
		(tags "resistor SMD 0402")
		(property "Reference" "R88"
			(at -1.25 15.3 0)
			(layer "F.SilkS")
			(effects
				(font
					(size 0.7 0.7)
					(thickness 0.15)
				)
				(justify left bottom)
			)
		)
		(property "Value" "R_100k_0402"
			(at -1.011843 1.772046 0)
			(layer "F.Fab")
			(hide yes)
			(effects
				(font
					(size 0.7 0.7)
					(thickness 0.15)
				)
				(justify left bottom)
			)
		)
		(property "Datasheet" "https://www.bourns.com/docs/product-datasheets/cr.pdf"
			(at 0 0 0)
			(layer "F.Fab")
			(hide yes)
			(effects
				(font
					(size 1.27 1.27)
					(thickness 0.15)
				)
			)
		)
		(property "Description" "SMD Chip Resistor, 100 kohm, ± 1%, 62.5 mW, 0402 [1005 Metric], Thick Film, General Purpose"
			(at 0 0 0)
			(layer "F.Fab")
			(hide yes)
			(effects
				(font
					(size 1.27 1.27)
					(thickness 0.15)
				)
			)
		)
		(property "MPN" "CR0402-FX-1003GLF"
			(at 0 0 0)
			(unlocked yes)
			(layer "F.Fab")
			(hide yes)
			(effects
				(font
					(size 1 1)
					(thickness 0.15)
				)
			)
		)
		(property "Manufacturer" "Bourns"
			(at 0 0 0)
			(unlocked yes)
			(layer "F.Fab")
			(hide yes)
			(effects
				(font
					(size 1 1)
					(thickness 0.15)
				)
			)
		)
		(property "License" "Apache-2.0"
			(at 0 0 0)
			(unlocked yes)
			(layer "F.Fab")
			(hide yes)
			(effects
				(font
					(size 1 1)
					(thickness 0.15)
				)
			)
		)
		(property "Author" "Antmicro"
			(at 0 0 0)
			(unlocked yes)
			(layer "F.Fab")
			(hide yes)
			(effects
				(font
					(size 1 1)
					(thickness 0.15)
				)
			)
		)
		(property "Val" "100k"
			(at 0 0 0)
			(unlocked yes)
			(layer "F.Fab")
			(hide yes)
			(effects
				(font
					(size 1 1)
					(thickness 0.15)
				)
			)
		)
		(property "Tolerance" "1%"
			(at 0 0 0)
			(unlocked yes)
			(layer "F.Fab")
			(hide yes)
			(effects
				(font
					(size 1 1)
					(thickness 0.15)
				)
			)
		)
		(sheetname "/X710-AT2 Misc/")
		(sheetfile "x710-at2-mics.kicad_sch")
		(attr smd)
		(fp_rect
			(start -0.925 -0.47)
			(end 0.925 0.47)
			(stroke
				(width 0.05)
				(type default)
			)
			(fill no)
			(layer "F.CrtYd")
		)
		(fp_rect
			(start -0.5 -0.25)
			(end 0.5 0.25)
			(stroke
				(width 0.15)
				(type solid)
			)
			(fill no)
			(layer "F.Fab")
		)
		(pad "1" smd roundrect
			(at -0.48 0)
			(size 0.59 0.64)
			(layers "F.Cu" "F.Mask" "F.Paste")
			(roundrect_rratio 0.25)
			(net 28 "GND")
			(pintype "passive")
		)
		(pad "2" smd roundrect
			(at 0.48 0)
			(size 0.59 0.64)
			(layers "F.Cu" "F.Mask" "F.Paste")
			(roundrect_rratio 0.25)
			(net 365 "/X710-AT2 Misc/NCSI.CRS_DV")
			(pintype "passive")
		)
	)
	(footprint "antmicro-footprints:R_0402_1005Metric"
		(layer "F.Cu")
		(at 69.8 91.305 90)
		(descr "Resistor SMD 0402")
		(tags "resistor SMD 0402")
		(property "Reference" "R110"
			(at 0.785 0.34 90)
			(layer "F.SilkS")
			(effects
				(font
					(size 0.7 0.7)
					(thickness 0.15)
				)
				(justify left bottom)
			)
		)
		(property "Value" "R_8k2_0402"
			(at -1.011843 1.772046 90)
			(layer "F.Fab")
			(hide yes)
			(effects
				(font
					(size 0.7 0.7)
					(thickness 0.15)
				)
				(justify left bottom)
			)
		)
		(property "Datasheet" "https://www.bourns.com/docs/product-datasheets/cr.pdf"
			(at 0 0 90)
			(layer "F.Fab")
			(hide yes)
			(effects
				(font
					(size 1.27 1.27)
					(thickness 0.15)
				)
			)
		)
		(property "Description" "SMD Chip Resistor"
			(at 0 0 90)
			(layer "F.Fab")
			(hide yes)
			(effects
				(font
					(size 1.27 1.27)
					(thickness 0.15)
				)
			)
		)
		(property "MPN" "CR0402-FX-8201GLF"
			(at 0 0 90)
			(unlocked yes)
			(layer "F.Fab")
			(hide yes)
			(effects
				(font
					(size 1 1)
					(thickness 0.15)
				)
			)
		)
		(property "Manufacturer" "Bourns"
			(at 0 0 90)
			(unlocked yes)
			(layer "F.Fab")
			(hide yes)
			(effects
				(font
					(size 1 1)
					(thickness 0.15)
				)
			)
		)
		(property "License" "Apache-2.0"
			(at 0 0 90)
			(unlocked yes)
			(layer "F.Fab")
			(hide yes)
			(effects
				(font
					(size 1 1)
					(thickness 0.15)
				)
			)
		)
		(property "Author" "Antmicro"
			(at 0 0 90)
			(unlocked yes)
			(layer "F.Fab")
			(hide yes)
			(effects
				(font
					(size 1 1)
					(thickness 0.15)
				)
			)
		)
		(property "Val" "8k2"
			(at 0 0 90)
			(unlocked yes)
			(layer "F.Fab")
			(hide yes)
			(effects
				(font
					(size 1 1)
					(thickness 0.15)
				)
			)
		)
		(property "Tolerance" "1%"
			(at 0 0 90)
			(unlocked yes)
			(layer "F.Fab")
			(hide yes)
			(effects
				(font
					(size 1 1)
					(thickness 0.15)
				)
			)
		)
		(sheetname "/X710-AT2 Misc/")
		(sheetfile "x710-at2-mics.kicad_sch")
		(attr smd)
		(fp_rect
			(start -0.925 -0.47)
			(end 0.925 0.47)
			(stroke
				(width 0.05)
				(type default)
			)
			(fill no)
			(layer "F.CrtYd")
		)
		(fp_rect
			(start -0.5 -0.25)
			(end 0.5 0.25)
			(stroke
				(width 0.15)
				(type solid)
			)
			(fill no)
			(layer "F.Fab")
		)
		(pad "1" smd roundrect
			(at -0.48 0 90)
			(size 0.59 0.64)
			(layers "F.Cu" "F.Mask" "F.Paste")
			(roundrect_rratio 0.25)
			(net 28 "GND")
			(pintype "passive")
		)
		(pad "2" smd roundrect
			(at 0.48 0 90)
			(size 0.59 0.64)
			(layers "F.Cu" "F.Mask" "F.Paste")
			(roundrect_rratio 0.25)
			(net 106 "/Flash memory/FLASH.CLK")
			(pintype "passive")
		)
	)
	(footprint "antmicro-footprints:C_0402_1005Metric"
		(layer "F.Cu")
		(at 57.099998 92.849999 -90)
		(descr "Capacitor SMD 0402")
		(tags "capacitor SMD 0402")
		(property "Reference" "C43"
			(at -1.819999 -0.350002 180)
			(layer "F.SilkS")
			(effects
				(font
					(size 0.7 0.7)
					(thickness 0.15)
				)
				(justify right top)
			)
		)
		(property "Value" "C_1u_25V_0402"
			(at -1.022927 2.155213 90)
			(layer "F.Fab")
			(hide yes)
			(effects
				(font
					(size 0.7 0.7)
					(thickness 0.15)
				)
				(justify right top)
			)
		)
		(property "Datasheet" "https://www.murata.com/products/productdetail?partno=GRM155R61E105KE11%23"
			(at 0 0 90)
			(layer "F.Fab")
			(hide yes)
			(effects
				(font
					(size 1.27 1.27)
					(thickness 0.15)
				)
			)
		)
		(property "Description" "SMD Multilayer Ceramic Capacitor, 1 µF, 25 V, 0402 [1005 Metric], ± 10%, X5R, GRM Series"
			(at 0 0 90)
			(layer "F.Fab")
			(hide yes)
			(effects
				(font
					(size 1.27 1.27)
					(thickness 0.15)
				)
			)
		)
		(property "MPN" "GRM155R61E105KE11J"
			(at 0 0 270)
			(unlocked yes)
			(layer "F.Fab")
			(hide yes)
			(effects
				(font
					(size 1 1)
					(thickness 0.15)
				)
			)
		)
		(property "Manufacturer" "Murata"
			(at 0 0 270)
			(unlocked yes)
			(layer "F.Fab")
			(hide yes)
			(effects
				(font
					(size 1 1)
					(thickness 0.15)
				)
			)
		)
		(property "License" "Apache-2.0"
			(at 0 0 270)
			(unlocked yes)
			(layer "F.Fab")
			(hide yes)
			(effects
				(font
					(size 1 1)
					(thickness 0.15)
				)
			)
		)
		(property "Author" "Antmicro"
			(at 0 0 270)
			(unlocked yes)
			(layer "F.Fab")
			(hide yes)
			(effects
				(font
					(size 1 1)
					(thickness 0.15)
				)
			)
		)
		(property "Val" "1u"
			(at 0 0 270)
			(unlocked yes)
			(layer "F.Fab")
			(hide yes)
			(effects
				(font
					(size 1 1)
					(thickness 0.15)
				)
			)
		)
		(property "Voltage" "25V"
			(at 0 0 270)
			(unlocked yes)
			(layer "F.Fab")
			(hide yes)
			(effects
				(font
					(size 1 1)
					(thickness 0.15)
				)
			)
		)
		(property "Dielectric" "X5R"
			(at 0 0 270)
			(unlocked yes)
			(layer "F.Fab")
			(hide yes)
			(effects
				(font
					(size 1 1)
					(thickness 0.15)
				)
			)
		)
		(sheetname "/Power/")
		(sheetfile "power.kicad_sch")
		(attr smd)
		(fp_rect
			(start -0.925 -0.47)
			(end 0.925 0.47)
			(stroke
				(width 0.05)
				(type default)
			)
			(fill no)
			(layer "F.CrtYd")
		)
		(fp_line
			(start -0.494 0.248)
			(end -0.494 -0.25)
			(stroke
				(width 0.15)
				(type solid)
			)
			(layer "F.Fab")
		)
		(fp_line
			(start 0.504 0.248)
			(end -0.494 0.248)
			(stroke
				(width 0.15)
				(type solid)
			)
			(layer "F.Fab")
		)
		(fp_line
			(start -0.494 -0.25)
			(end 0.504 -0.25)
			(stroke
				(width 0.15)
				(type solid)
			)
			(layer "F.Fab")
		)
		(fp_line
			(start 0.504 -0.25)
			(end 0.504 0.248)
			(stroke
				(width 0.15)
				(type solid)
			)
			(layer "F.Fab")
		)
		(pad "1" smd roundrect
			(at -0.48 0 270)
			(size 0.59 0.64)
			(layers "F.Cu" "F.Mask" "F.Paste")
			(roundrect_rratio 0.25)
			(net 28 "GND")
			(pintype "passive")
		)
		(pad "2" smd roundrect
			(at 0.48 0 270)
			(size 0.59 0.64)
			(layers "F.Cu" "F.Mask" "F.Paste")
			(roundrect_rratio 0.25)
			(net 326 "/Power/DVDD_VCC")
			(pintype "passive")
		)
	)
)
